# T6G (Grand Teton) — schematic netlist excerpt (pin names and nets, part order shuffled) for the footprints in the layout excerpt that follows; sources: Cadence DE-HDL packaged netlist, KiCad conversion of 04192023_DAF0TMB3IC0_F0TG_MB_C_brd_V02_OCP.brd

PL6501  Q_INDUCTOR  1UH IND  pkg SMLF  page 360 : \1\ = SW_P1V8_RETIMER_CPU0_SW ; \2\ = P1V8_CPU0_RT_1D
R3687  Q_RES  0 5% EMPTY  pkg 0402LF  page 257 : A = P1V581_PDB_ADC ; B = P3V3_PDB_AUX_ADC_MAM
R837  Q_RES  1K 1% CHIP  pkg 0201LF  page 185 : A = P1V8_CPU0_RT_1D ; B = SMB_RT_CPU0_P1_ROM_R_SCL

(kicad_pcb
	(version 20260206)
	(generator "pcbnew")
	(generator_version "10.0")
	(general
		(thickness 1.6)
		(legacy_teardrops no)
	)
	(paper "A4")
	(title_block
		(title "04192023_DAF0TMB3IC0_F0TG_MB_C_brd_V02_OCP.brd")
		(comment 1 "Grand Teton / footprints 4503-4506 of 8354")
	)
	(layers
		(0 "F.Cu" signal "TOP")
		(4 "In1.Cu" signal "GND")
		(6 "In2.Cu" signal "IN1")
		(8 "In3.Cu" signal "GND1")
		(10 "In4.Cu" signal "IN2")
		(12 "In5.Cu" signal "GND2")
		(14 "In6.Cu" signal "IN3")
		(16 "In7.Cu" signal "GND3")
		(18 "In8.Cu" signal "VCC")
		(20 "In9.Cu" signal "VCC1")
		(22 "In10.Cu" signal "GND4")
		(24 "In11.Cu" signal "IN4")
		(26 "In12.Cu" signal "GND5")
		(28 "In13.Cu" signal "IN5")
		(30 "In14.Cu" signal "GND6")
		(32 "In15.Cu" signal "IN6")
		(34 "In16.Cu" signal "GND7")
		(2 "B.Cu" signal "BOTTOM")
		(9 "F.Adhes" user "F.Adhesive")
		(11 "B.Adhes" user "B.Adhesive")
		(13 "F.Paste" user "Package Geometry/Pastemask Top")
		(15 "B.Paste" user "Package Geometry/Pastemask Bottom")
		(5 "F.SilkS" user "Ref Des/Silkscreen Top")
		(7 "B.SilkS" user "Ref Des/Silkscreen Bottom")
		(1 "F.Mask" user "Board Geometry/Soldermask Top")
		(3 "B.Mask" user "Board Geometry/Soldermask Bottom")
		(17 "Dwgs.User" user "User.Drawings")
		(19 "Cmts.User" user "User.Comments")
		(21 "Eco1.User" user "User.Eco1")
		(23 "Eco2.User" user "User.Eco2")
		(25 "Edge.Cuts" user "Board Geometry/Outline")
		(27 "Margin" user)
		(31 "F.CrtYd" user "Package Geometry/Place Bound Top")
		(29 "B.CrtYd" user "Package Geometry/Place Bound Bottom")
		(35 "F.Fab" user "Ref Des/Assembly Top")
		(33 "B.Fab" user "Ref Des/Assembly Bottom")
	)
	(footprint ""
		(layer "F.Cu")
		(at 323.637148 -40.144954)
		(property "Reference" "R3687"
			(at 0 0 0)
			(layer "F.SilkS")
			(hide yes)
			(effects
				(font
					(size 1.27 1.27)
				)
			)
		)
		(property "Value" ""
			(at 0 0 0)
			(layer "F.Fab")
			(effects
				(font
					(size 1.27 1.27)
				)
			)
		)
		(duplicate_pad_numbers_are_jumpers no)
		(fp_line
			(start -0.7874 -0.4064)
			(end 0.7874 -0.4064)
			(stroke
				(width 0.1524)
				(type default)
			)
			(layer "F.SilkS")
		)
		(fp_line
			(start -0.7874 0.4064)
			(end -0.7874 -0.4064)
			(stroke
				(width 0.1524)
				(type default)
			)
			(layer "F.SilkS")
		)
		(fp_line
			(start 0.7874 -0.4064)
			(end 0.7874 0.4064)
			(stroke
				(width 0.1524)
				(type default)
			)
			(layer "F.SilkS")
		)
		(fp_line
			(start 0.7874 0.4064)
			(end -0.7874 0.4064)
			(stroke
				(width 0.1524)
				(type default)
			)
			(layer "F.SilkS")
		)
		(fp_line
			(start -0.67945 -0.305054)
			(end -0.12065 -0.305054)
			(stroke
				(width 0.1)
				(type default)
			)
			(layer "F.Fab")
		)
		(fp_line
			(start -0.67945 0.3048)
			(end -0.67945 -0.305054)
			(stroke
				(width 0.1)
				(type default)
			)
			(layer "F.Fab")
		)
		(fp_line
			(start -0.12065 -0.305054)
			(end -0.12065 -0.2794)
			(stroke
				(width 0.1)
				(type default)
			)
			(layer "F.Fab")
		)
		(fp_line
			(start -0.12065 -0.2794)
			(end 0.12065 -0.2794)
			(stroke
				(width 0.1)
				(type default)
			)
			(layer "F.Fab")
		)
		(fp_line
			(start -0.12065 0.2794)
			(end -0.12065 0.3048)
			(stroke
				(width 0.1)
				(type default)
			)
			(layer "F.Fab")
		)
		(fp_line
			(start -0.12065 0.3048)
			(end -0.67945 0.3048)
			(stroke
				(width 0.1)
				(type default)
			)
			(layer "F.Fab")
		)
		(fp_line
			(start 0.120396 0.2794)
			(end -0.12065 0.2794)
			(stroke
				(width 0.1)
				(type default)
			)
			(layer "F.Fab")
		)
		(fp_line
			(start 0.120396 0.3048)
			(end 0.120396 0.2794)
			(stroke
				(width 0.1)
				(type default)
			)
			(layer "F.Fab")
		)
		(fp_line
			(start 0.12065 -0.3048)
			(end 0.67945 -0.3048)
			(stroke
				(width 0.1)
				(type default)
			)
			(layer "F.Fab")
		)
		(fp_line
			(start 0.12065 -0.2794)
			(end 0.12065 -0.3048)
			(stroke
				(width 0.1)
				(type default)
			)
			(layer "F.Fab")
		)
		(fp_line
			(start 0.67945 -0.3048)
			(end 0.67945 0.3048)
			(stroke
				(width 0.1)
				(type default)
			)
			(layer "F.Fab")
		)
		(fp_line
			(start 0.67945 0.3048)
			(end 0.120396 0.3048)
			(stroke
				(width 0.1)
				(type default)
			)
			(layer "F.Fab")
		)
		(pad "1" smd rect
			(at -0.40005 0 180)
			(size 0.4572 0.508)
			(layers "F.Cu" "F.Mask" "F.Paste")
			(net "P1V581_PDB_ADC")
		)
		(pad "2" smd rect
			(at 0.40005 0 180)
			(size 0.4572 0.508)
			(layers "F.Cu" "F.Mask" "F.Paste")
			(net "P3V3_PDB_AUX_ADC_MAM")
		)
	)
	(footprint ""
		(layer "F.Cu")
		(at 242.952016 -304.162206 90)
		(property "Reference" "PL6501"
			(at -7.490206 7.391654 90)
			(unlocked yes)
			(layer "F.SilkS")
			(effects
				(font
					(size 0.7874 0.5842)
					(thickness 0.1524)
				)
				(justify left)
			)
		)
		(property "Value" ""
			(at 0 0 90)
			(layer "F.Fab")
			(effects
				(font
					(size 1.27 1.27)
				)
			)
		)
		(duplicate_pad_numbers_are_jumpers no)
		(fp_line
			(start 7.4422 -6.400038)
			(end 7.4422 6.400038)
			(stroke
				(width 0.1524)
				(type default)
			)
			(layer "F.SilkS")
		)
		(fp_line
			(start -7.4422 -6.400038)
			(end 7.4422 -6.400038)
			(stroke
				(width 0.1524)
				(type default)
			)
			(layer "F.SilkS")
		)
		(fp_line
			(start 7.4422 6.400038)
			(end -7.4422 6.400038)
			(stroke
				(width 0.1524)
				(type default)
			)
			(layer "F.SilkS")
		)
		(fp_line
			(start -7.4422 6.400038)
			(end -7.4422 -6.400038)
			(stroke
				(width 0.1524)
				(type default)
			)
			(layer "F.SilkS")
		)
		(fp_line
			(start 6.938264 -6.400038)
			(end -6.862064 -6.400038)
			(stroke
				(width 0.1)
				(type default)
			)
			(layer "F.Fab")
		)
		(fp_line
			(start -6.862064 -6.400038)
			(end -6.862064 6.400038)
			(stroke
				(width 0.1)
				(type default)
			)
			(layer "F.Fab")
		)
		(fp_line
			(start 6.938264 6.400038)
			(end 6.938264 -6.400038)
			(stroke
				(width 0.1)
				(type default)
			)
			(layer "F.Fab")
		)
		(fp_line
			(start -6.862064 6.400038)
			(end 6.938264 6.400038)
			(stroke
				(width 0.1)
				(type default)
			)
			(layer "F.Fab")
		)
		(pad "1" smd rect
			(at -5.650484 0 90)
			(size 3.302 4.29768)
			(layers "F.Cu" "F.Mask" "F.Paste")
			(net "SW_P1V8_RETIMER_CPU0_SW")
		)
		(pad "2" smd rect
			(at 5.650484 0 90)
			(size 3.302 4.29768)
			(layers "F.Cu" "F.Mask" "F.Paste")
			(net "P1V8_CPU0_RT_1D")
		)
	)
	(footprint ""
		(layer "F.Cu")
		(at 290.15944 -397.589248)
		(property "Reference" "R837"
			(at 0 0 0)
			(layer "F.SilkS")
			(hide yes)
			(effects
				(font
					(size 1.27 1.27)
				)
			)
		)
		(property "Value" ""
			(at 0 0 0)
			(layer "F.Fab")
			(effects
				(font
					(size 1.27 1.27)
				)
			)
		)
		(duplicate_pad_numbers_are_jumpers no)
		(fp_line
			(start -0.32512 -0.175006)
			(end 0.32512 -0.175006)
			(stroke
				(width 0.1)
				(type default)
			)
			(layer "F.Fab")
		)
		(fp_line
			(start -0.32512 0.175006)
			(end -0.32512 -0.175006)
			(stroke
				(width 0.1)
				(type default)
			)
			(layer "F.Fab")
		)
		(fp_line
			(start 0.32512 -0.175006)
			(end 0.32512 0.175006)
			(stroke
				(width 0.1)
				(type default)
			)
			(layer "F.Fab")
		)
		(fp_line
			(start 0.32512 0.175006)
			(end -0.32512 0.175006)
			(stroke
				(width 0.1)
				(type default)
			)
			(layer "F.Fab")
		)
		(pad "1" smd rect
			(at -0.2667 0)
			(size 0.3048 0.381)
			(layers "F.Cu" "F.Mask" "F.Paste")
			(net "P1V8_CPU0_RT_1D")
		)
		(pad "2" smd rect
			(at 0.2667 0 180)
			(size 0.3048 0.381)
			(layers "F.Cu" "F.Mask" "F.Paste")
			(net "SMB_RT_CPU0_P1_ROM_R_SCL")
		)
	)
	(footprint ""
		(layer "F.Cu")
		(at 43.012106 19.444716 -90)
		(property "Reference" "PJ38_NUT"
			(at 0 0 270)
			(layer "F.SilkS")
			(hide yes)
			(effects
				(font
					(size 1.27 1.27)
				)
			)
		)
		(property "Value" ""
			(at 0 0 270)
			(layer "F.Fab")
			(effects
				(font
					(size 1.27 1.27)
				)
			)
		)
		(duplicate_pad_numbers_are_jumpers no)
		(pad "1" smd circle
			(at 0 0 270)
			(size 0.762 0.762)
			(layers "F.Cu" "F.Mask" "F.Paste")
			(net "Net_10790")
		)
	)
)
